# S9S_MB_2U (Grand Teton) — schematic netlist excerpt (pin names and nets, part order shuffled) for the footprints in the layout excerpt that follows; sources: Cadence DE-HDL packaged netlist, KiCad conversion of 03242023_DA0F0TMBIJ0_F0T_Motherboard_J_brd_V01_OCP.brd

R4174  Q_RES  33.2 1% CHIP  pkg 0402LF  page 215 : A = RST_PCIE_PCH_DEV_PERST_N ; B = RST_PCIE_PCH_DEV_PERST_E1S_R_N
PC2152  Q_CAP  0.1UF 25V 10% X7R  pkg 0402  page 162 : A = P12V_OCP_V3_2 ; B = GND

(kicad_pcb
	(version 20260206)
	(generator "pcbnew")
	(generator_version "10.0")
	(general
		(thickness 1.6)
		(legacy_teardrops no)
	)
	(paper "A4")
	(title_block
		(title "03242023_DA0F0TMBIJ0_F0T_Motherboard_J_brd_V01_OCP.brd")
		(comment 1 "Grand Teton / footprints 656-657 of 6105")
	)
	(layers
		(0 "F.Cu" signal "TOP")
		(4 "In1.Cu" signal "GND")
		(6 "In2.Cu" signal "IN1")
		(8 "In3.Cu" signal "GND1")
		(10 "In4.Cu" signal "IN2")
		(12 "In5.Cu" signal "GND2")
		(14 "In6.Cu" signal "IN3")
		(16 "In7.Cu" signal "GND3")
		(18 "In8.Cu" signal "VCC")
		(20 "In9.Cu" signal "VCC1")
		(22 "In10.Cu" signal "GND4")
		(24 "In11.Cu" signal "IN4")
		(26 "In12.Cu" signal "GND5")
		(28 "In13.Cu" signal "IN5")
		(30 "In14.Cu" signal "GND6")
		(32 "In15.Cu" signal "IN6")
		(34 "In16.Cu" signal "GND7")
		(2 "B.Cu" signal "BOTTOM")
		(9 "F.Adhes" user "F.Adhesive")
		(11 "B.Adhes" user "B.Adhesive")
		(13 "F.Paste" user "Package Geometry/Pastemask Top")
		(15 "B.Paste" user "Package Geometry/Pastemask Bottom")
		(5 "F.SilkS" user "Ref Des/Silkscreen Top")
		(7 "B.SilkS" user "Ref Des/Silkscreen Bottom")
		(1 "F.Mask" user "Board Geometry/Soldermask Top")
		(3 "B.Mask" user "Board Geometry/Soldermask Bottom")
		(17 "Dwgs.User" user "User.Drawings")
		(19 "Cmts.User" user "User.Comments")
		(21 "Eco1.User" user "User.Eco1")
		(23 "Eco2.User" user "User.Eco2")
		(25 "Edge.Cuts" user "Board Geometry/Outline")
		(27 "Margin" user)
		(31 "F.CrtYd" user "Package Geometry/Place Bound Top")
		(29 "B.CrtYd" user "Package Geometry/Place Bound Bottom")
		(35 "F.Fab" user "Ref Des/Assembly Top")
		(33 "B.Fab" user "Ref Des/Assembly Bottom")
	)
	(footprint ""
		(layer "F.Cu")
		(at 204.93736 -120.614948)
		(property "Reference" "R4174"
			(at 0 0 0)
			(layer "F.SilkS")
			(hide yes)
			(effects
				(font
					(size 1.27 1.27)
				)
			)
		)
		(property "Value" ""
			(at 0 0 0)
			(layer "F.Fab")
			(effects
				(font
					(size 1.27 1.27)
				)
			)
		)
		(duplicate_pad_numbers_are_jumpers no)
		(fp_line
			(start -0.7874 -0.4064)
			(end 0.7874 -0.4064)
			(stroke
				(width 0.1524)
				(type default)
			)
			(layer "F.SilkS")
		)
		(fp_line
			(start -0.7874 0.4064)
			(end -0.7874 -0.4064)
			(stroke
				(width 0.1524)
				(type default)
			)
			(layer "F.SilkS")
		)
		(fp_line
			(start 0.7874 -0.4064)
			(end 0.7874 0.4064)
			(stroke
				(width 0.1524)
				(type default)
			)
			(layer "F.SilkS")
		)
		(fp_line
			(start 0.7874 0.4064)
			(end -0.7874 0.4064)
			(stroke
				(width 0.1524)
				(type default)
			)
			(layer "F.SilkS")
		)
		(fp_line
			(start -0.67945 -0.305054)
			(end -0.12065 -0.305054)
			(stroke
				(width 0.1)
				(type default)
			)
			(layer "F.Fab")
		)
		(fp_line
			(start -0.67945 0.3048)
			(end -0.67945 -0.305054)
			(stroke
				(width 0.1)
				(type default)
			)
			(layer "F.Fab")
		)
		(fp_line
			(start -0.12065 -0.305054)
			(end -0.12065 -0.2794)
			(stroke
				(width 0.1)
				(type default)
			)
			(layer "F.Fab")
		)
		(fp_line
			(start -0.12065 -0.2794)
			(end 0.12065 -0.2794)
			(stroke
				(width 0.1)
				(type default)
			)
			(layer "F.Fab")
		)
		(fp_line
			(start -0.12065 0.2794)
			(end -0.12065 0.3048)
			(stroke
				(width 0.1)
				(type default)
			)
			(layer "F.Fab")
		)
		(fp_line
			(start -0.12065 0.3048)
			(end -0.67945 0.3048)
			(stroke
				(width 0.1)
				(type default)
			)
			(layer "F.Fab")
		)
		(fp_line
			(start 0.120396 0.2794)
			(end -0.12065 0.2794)
			(stroke
				(width 0.1)
				(type default)
			)
			(layer "F.Fab")
		)
		(fp_line
			(start 0.120396 0.3048)
			(end 0.120396 0.2794)
			(stroke
				(width 0.1)
				(type default)
			)
			(layer "F.Fab")
		)
		(fp_line
			(start 0.12065 -0.3048)
			(end 0.67945 -0.3048)
			(stroke
				(width 0.1)
				(type default)
			)
			(layer "F.Fab")
		)
		(fp_line
			(start 0.12065 -0.2794)
			(end 0.12065 -0.3048)
			(stroke
				(width 0.1)
				(type default)
			)
			(layer "F.Fab")
		)
		(fp_line
			(start 0.67945 -0.3048)
			(end 0.67945 0.3048)
			(stroke
				(width 0.1)
				(type default)
			)
			(layer "F.Fab")
		)
		(fp_line
			(start 0.67945 0.3048)
			(end 0.120396 0.3048)
			(stroke
				(width 0.1)
				(type default)
			)
			(layer "F.Fab")
		)
		(pad "1" smd circle
			(at -0.40005 0)
			(size 0 0)
			(layers "F.Cu" "F.Mask" "F.Paste")
			(net "RST_PCIE_PCH_DEV_PERST_N")
		)
		(pad "2" smd circle
			(at 0.40005 0)
			(size 0 0)
			(layers "F.Cu" "F.Mask" "F.Paste")
			(net "RST_PCIE_PCH_DEV_PERST_E1S_R_N")
		)
	)
	(footprint ""
		(layer "F.Cu")
		(at 66.150744 -14.26464 180)
		(property "Reference" "PC2152"
			(at 0 0 180)
			(layer "F.SilkS")
			(hide yes)
			(effects
				(font
					(size 1.27 1.27)
				)
			)
		)
		(property "Value" ""
			(at 0 0 180)
			(layer "F.Fab")
			(effects
				(font
					(size 1.27 1.27)
				)
			)
		)
		(duplicate_pad_numbers_are_jumpers no)
		(fp_line
			(start 0.7874 0.4064)
			(end -0.7874 0.4064)
			(stroke
				(width 0.1524)
				(type default)
			)
			(layer "F.SilkS")
		)
		(fp_line
			(start 0.7874 -0.4064)
			(end 0.7874 0.4064)
			(stroke
				(width 0.1524)
				(type default)
			)
			(layer "F.SilkS")
		)
		(fp_line
			(start -0.7874 0.4064)
			(end -0.7874 -0.4064)
			(stroke
				(width 0.1524)
				(type default)
			)
			(layer "F.SilkS")
		)
		(fp_line
			(start -0.7874 -0.4064)
			(end 0.7874 -0.4064)
			(stroke
				(width 0.1524)
				(type default)
			)
			(layer "F.SilkS")
		)
		(fp_line
			(start 0.67945 0.3048)
			(end 0.120396 0.3048)
			(stroke
				(width 0.1)
				(type default)
			)
			(layer "F.Fab")
		)
		(fp_line
			(start 0.67945 -0.3048)
			(end 0.67945 0.3048)
			(stroke
				(width 0.1)
				(type default)
			)
			(layer "F.Fab")
		)
		(fp_line
			(start 0.12065 -0.2794)
			(end 0.12065 -0.3048)
			(stroke
				(width 0.1)
				(type default)
			)
			(layer "F.Fab")
		)
		(fp_line
			(start 0.12065 -0.3048)
			(end 0.67945 -0.3048)
			(stroke
				(width 0.1)
				(type default)
			)
			(layer "F.Fab")
		)
		(fp_line
			(start 0.120396 0.3048)
			(end 0.120396 0.2794)
			(stroke
				(width 0.1)
				(type default)
			)
			(layer "F.Fab")
		)
		(fp_line
			(start 0.120396 0.2794)
			(end -0.12065 0.2794)
			(stroke
				(width 0.1)
				(type default)
			)
			(layer "F.Fab")
		)
		(fp_line
			(start -0.12065 0.3048)
			(end -0.67945 0.3048)
			(stroke
				(width 0.1)
				(type default)
			)
			(layer "F.Fab")
		)
		(fp_line
			(start -0.12065 0.2794)
			(end -0.12065 0.3048)
			(stroke
				(width 0.1)
				(type default)
			)
			(layer "F.Fab")
		)
		(fp_line
			(start -0.12065 -0.2794)
			(end 0.12065 -0.2794)
			(stroke
				(width 0.1)
				(type default)
			)
			(layer "F.Fab")
		)
		(fp_line
			(start -0.12065 -0.305054)
			(end -0.12065 -0.2794)
			(stroke
				(width 0.1)
				(type default)
			)
			(layer "F.Fab")
		)
		(fp_line
			(start -0.67945 0.3048)
			(end -0.67945 -0.305054)
			(stroke
				(width 0.1)
				(type default)
			)
			(layer "F.Fab")
		)
		(fp_line
			(start -0.67945 -0.305054)
			(end -0.12065 -0.305054)
			(stroke
				(width 0.1)
				(type default)
			)
			(layer "F.Fab")
		)
		(pad "1" smd circle
			(at -0.40005 0 180)
			(size 0 0)
			(layers "F.Cu" "F.Mask" "F.Paste")
			(net "P12V_OCP_V3_2")
		)
		(pad "2" smd circle
			(at 0.40005 0 180)
			(size 0 0)
			(layers "F.Cu" "F.Mask" "F.Paste")
			(net "GND")
		)
	)
)
